(kicad_pcb
	(version 20241229)
	(generator "pcbnew")
	(generator_version "9.0")
	(general
		(thickness 1.62)
		(legacy_teardrops no)
	)
	(paper "A3")
	(title_block
		(title "COM Express 7 Baseboard")
		(date "2025-02-04")
		(rev "1.1.2")
		(company "Antmicro Ltd")
		(comment 1 "www.antmicro.com")
		(comment 9 "footprints 530-535 of 802")
	)
	(layers
		(0 "F.Cu" signal)
		(4 "In1.Cu" signal)
		(6 "In2.Cu" signal)
		(8 "In3.Cu" signal)
		(10 "In4.Cu" signal)
		(12 "In5.Cu" signal)
		(14 "In6.Cu" signal)
		(2 "B.Cu" signal)
		(9 "F.Adhes" user "F.Adhesive")
		(11 "B.Adhes" user "B.Adhesive")
		(13 "F.Paste" user)
		(15 "B.Paste" user)
		(5 "F.SilkS" user "F.Silkscreen")
		(7 "B.SilkS" user "B.Silkscreen")
		(1 "F.Mask" user)
		(3 "B.Mask" user)
		(17 "Dwgs.User" user "User.Drawings")
		(19 "Cmts.User" user "User.Comments")
		(21 "Eco1.User" user "User.Eco1")
		(23 "Eco2.User" user "User.Eco2")
		(25 "Edge.Cuts" user)
		(27 "Margin" user)
		(31 "F.CrtYd" user "F.Courtyard")
		(29 "B.CrtYd" user "B.Courtyard")
		(35 "F.Fab" user)
		(33 "B.Fab" user)
	)
	(footprint "antmicro-footprints:C_0603_1608Metric"
		(layer "B.Cu")
		(at 237.495708 74.06 180)
		(descr "Capacitor SMD 0603")
		(tags "capacitor 0603")
		(property "Reference" "C7"
			(at -0.825 -1.55 0)
			(layer "B.SilkS")
			(effects
				(font
					(size 0.7 0.7)
					(thickness 0.15)
				)
				(justify left bottom mirror)
			)
		)
		(property "Value" "C_22u_16V_0603"
			(at -1.42757 -1.770288 0)
			(layer "B.Fab")
			(effects
				(font
					(size 0.7 0.7)
					(thickness 0.15)
				)
				(justify left bottom mirror)
			)
		)
		(property "Datasheet" "https://product.samsungsem.com/mlcc/CL10A226MO7JZN.do"
			(at 0 0 180)
			(layer "F.Fab")
			(hide yes)
			(effects
				(font
					(size 1.27 1.27)
					(thickness 0.15)
				)
			)
		)
		(property "Author" "Antmicro"
			(at 474.991416 148.12 0)
			(layer "B.Fab")
			(hide yes)
			(effects
				(font
					(size 1 1)
					(thickness 0.15)
				)
				(justify mirror)
			)
		)
		(property "Dielectric" ""
			(at 474.991416 148.12 0)
			(layer "B.Fab")
			(hide yes)
			(effects
				(font
					(size 1 1)
					(thickness 0.15)
				)
				(justify mirror)
			)
		)
		(property "License" "Apache-2.0"
			(at 474.991416 148.12 0)
			(layer "B.Fab")
			(hide yes)
			(effects
				(font
					(size 1 1)
					(thickness 0.15)
				)
				(justify mirror)
			)
		)
		(property "MPN" "CL10A226MO7JZNC"
			(at 474.991416 148.12 0)
			(layer "B.Fab")
			(hide yes)
			(effects
				(font
					(size 1 1)
					(thickness 0.15)
				)
				(justify mirror)
			)
		)
		(property "Manufacturer" "Samsung Electro-Mechanics"
			(at 474.991416 148.12 0)
			(layer "B.Fab")
			(hide yes)
			(effects
				(font
					(size 1 1)
					(thickness 0.15)
				)
				(justify mirror)
			)
		)
		(property "Public" "False"
			(at 474.991416 148.12 0)
			(layer "B.Fab")
			(hide yes)
			(effects
				(font
					(size 1 1)
					(thickness 0.15)
				)
				(justify mirror)
			)
		)
		(property "Val" "22u"
			(at 474.991416 148.12 0)
			(layer "B.Fab")
			(hide yes)
			(effects
				(font
					(size 1 1)
					(thickness 0.15)
				)
				(justify mirror)
			)
		)
		(property "Voltage" "16V"
			(at 474.991416 148.12 0)
			(layer "B.Fab")
			(hide yes)
			(effects
				(font
					(size 1 1)
					(thickness 0.15)
				)
				(justify mirror)
			)
		)
		(sheetname "Misc")
		(sheetfile "misc.kicad_sch")
		(attr smd)
		(fp_line
			(start 0.15 0.4)
			(end -0.15 0.4)
			(stroke
				(width 0.15)
				(type solid)
			)
			(layer "B.SilkS")
		)
		(fp_line
			(start 0.15 -0.4)
			(end -0.15 -0.4)
			(stroke
				(width 0.15)
				(type solid)
			)
			(layer "B.SilkS")
		)
		(fp_rect
			(start -1.25 0.65)
			(end 1.25 -0.65)
			(stroke
				(width 0.05)
				(type solid)
			)
			(fill no)
			(layer "B.CrtYd")
		)
		(fp_rect
			(start -0.8 0.4)
			(end 0.8 -0.4)
			(stroke
				(width 0.15)
				(type solid)
			)
			(fill no)
			(layer "B.Fab")
		)
		(pad "1" smd roundrect
			(at -0.7 0 180)
			(size 0.8 1)
			(layers "B.Cu" "B.Mask" "B.Paste")
			(roundrect_rratio 0.2)
			(net 1 "GND")
			(pintype "passive")
			(teardrops
				(best_length_ratio 0.2)
				(max_length 1)
				(best_width_ratio 0.9)
				(max_width 2)
				(curved_edges yes)
				(filter_ratio 0.9)
				(enabled yes)
				(allow_two_segments yes)
				(prefer_zone_connections yes)
			)
		)
		(pad "2" smd roundrect
			(at 0.7 0 180)
			(size 0.8 1)
			(layers "B.Cu" "B.Mask" "B.Paste")
			(roundrect_rratio 0.2)
			(net 81 "/Misc/FAN_12V")
			(pintype "passive")
			(teardrops
				(best_length_ratio 0.2)
				(max_length 1)
				(best_width_ratio 0.9)
				(max_width 2)
				(curved_edges yes)
				(filter_ratio 0.9)
				(enabled yes)
				(allow_two_segments yes)
				(prefer_zone_connections yes)
			)
		)
	)
	(footprint "antmicro-footprints:C_0402_1005Metric"
		(layer "B.Cu")
		(at 132.29 138.36 -90)
		(descr "Capacitor SMD 0402")
		(tags "capacitor SMD 0402")
		(property "Reference" "C199"
			(at -0.35 0.54 90)
			(layer "B.SilkS")
			(effects
				(font
					(size 0.7 0.7)
					(thickness 0.15)
				)
				(justify left bottom mirror)
			)
		)
		(property "Value" "C_100n_0402"
			(at -1.022927 -2.155213 90)
			(layer "B.Fab")
			(effects
				(font
					(size 0.7 0.7)
					(thickness 0.15)
				)
				(justify left bottom mirror)
			)
		)
		(property "Datasheet" "https://www.murata.com/products/productdetail?partno=GRM155R61H104KE14%23"
			(at 0 0 270)
			(layer "F.Fab")
			(hide yes)
			(effects
				(font
					(size 1.27 1.27)
					(thickness 0.15)
				)
			)
		)
		(property "Author" "Antmicro"
			(at -6.07 270.65 0)
			(layer "B.Fab")
			(hide yes)
			(effects
				(font
					(size 1 1)
					(thickness 0.15)
				)
				(justify mirror)
			)
		)
		(property "Dielectric" "X5R"
			(at -6.07 270.65 0)
			(layer "B.Fab")
			(hide yes)
			(effects
				(font
					(size 1 1)
					(thickness 0.15)
				)
				(justify mirror)
			)
		)
		(property "License" "Apache-2.0"
			(at -6.07 270.65 0)
			(layer "B.Fab")
			(hide yes)
			(effects
				(font
					(size 1 1)
					(thickness 0.15)
				)
				(justify mirror)
			)
		)
		(property "MPN" "GRM155R61H104KE14D"
			(at -6.07 270.65 0)
			(layer "B.Fab")
			(hide yes)
			(effects
				(font
					(size 1 1)
					(thickness 0.15)
				)
				(justify mirror)
			)
		)
		(property "Manufacturer" "Murata"
			(at -6.07 270.65 0)
			(layer "B.Fab")
			(hide yes)
			(effects
				(font
					(size 1 1)
					(thickness 0.15)
				)
				(justify mirror)
			)
		)
		(property "Public" "False"
			(at -6.07 270.65 0)
			(layer "B.Fab")
			(hide yes)
			(effects
				(font
					(size 1 1)
					(thickness 0.15)
				)
				(justify mirror)
			)
		)
		(property "Val" "100n"
			(at -6.07 270.65 0)
			(layer "B.Fab")
			(hide yes)
			(effects
				(font
					(size 1 1)
					(thickness 0.15)
				)
				(justify mirror)
			)
		)
		(property "Voltage" "50V"
			(at -6.07 270.65 0)
			(layer "B.Fab")
			(hide yes)
			(effects
				(font
					(size 1 1)
					(thickness 0.15)
				)
				(justify mirror)
			)
		)
		(sheetname "KR to SFI #2")
		(sheetfile "kr_sfi.kicad_sch")
		(attr smd)
		(fp_rect
			(start -0.925 0.47)
			(end 0.925 -0.47)
			(stroke
				(width 0.05)
				(type default)
			)
			(fill no)
			(layer "B.CrtYd")
		)
		(fp_line
			(start -0.494 0.25)
			(end -0.494 -0.248)
			(stroke
				(width 0.15)
				(type solid)
			)
			(layer "B.Fab")
		)
		(fp_line
			(start 0.504 0.25)
			(end -0.494 0.25)
			(stroke
				(width 0.15)
				(type solid)
			)
			(layer "B.Fab")
		)
		(fp_line
			(start -0.494 -0.248)
			(end 0.504 -0.248)
			(stroke
				(width 0.15)
				(type solid)
			)
			(layer "B.Fab")
		)
		(fp_line
			(start 0.504 -0.248)
			(end 0.504 0.25)
			(stroke
				(width 0.15)
				(type solid)
			)
			(layer "B.Fab")
		)
		(pad "1" smd roundrect
			(at -0.48 0 270)
			(size 0.59 0.64)
			(layers "B.Cu" "B.Mask" "B.Paste")
			(roundrect_rratio 0.25)
			(net 1 "GND")
			(pintype "passive")
			(teardrops
				(best_length_ratio 0.2)
				(max_length 1)
				(best_width_ratio 0.9)
				(max_width 2)
				(curved_edges yes)
				(filter_ratio 0.9)
				(enabled yes)
				(allow_two_segments yes)
				(prefer_zone_connections yes)
			)
		)
		(pad "2" smd roundrect
			(at 0.48 0 270)
			(size 0.59 0.64)
			(layers "B.Cu" "B.Mask" "B.Paste")
			(roundrect_rratio 0.25)
			(net 74 "+1V0")
			(pintype "passive")
			(teardrops
				(best_length_ratio 0.2)
				(max_length 1)
				(best_width_ratio 0.9)
				(max_width 2)
				(curved_edges yes)
				(filter_ratio 0.9)
				(enabled yes)
				(allow_two_segments yes)
				(prefer_zone_connections yes)
			)
		)
	)
	(footprint "antmicro-footprints:TP_SMD_0.75mm"
		(layer "B.Cu")
		(at 186.7 169.9 180)
		(property "Reference" "TP34"
			(at 0.45 0.499999 0)
			(layer "B.SilkS")
			(effects
				(font
					(size 0.7 0.7)
					(thickness 0.15)
				)
				(justify left top mirror)
			)
		)
		(property "Value" "TP_0.75mm_SMD"
			(at 0 -1.2 0)
			(layer "B.Fab")
			(effects
				(font
					(size 0.7 0.7)
					(thickness 0.15)
				)
				(justify left top mirror)
			)
		)
		(property "Author" "Antmicro"
			(at 363.960001 -65.84 90)
			(layer "B.Fab")
			(hide yes)
			(effects
				(font
					(size 1 1)
					(thickness 0.15)
				)
				(justify mirror)
			)
		)
		(property "License" "Apache-2.0"
			(at 363.960001 -65.84 90)
			(layer "B.Fab")
			(hide yes)
			(effects
				(font
					(size 1 1)
					(thickness 0.15)
				)
				(justify mirror)
			)
		)
		(property "MPN" ""
			(at 363.960001 -65.84 90)
			(layer "B.Fab")
			(hide yes)
			(effects
				(font
					(size 1 1)
					(thickness 0.15)
				)
				(justify mirror)
			)
		)
		(property "Manufacturer" ""
			(at 363.960001 -65.84 90)
			(layer "B.Fab")
			(hide yes)
			(effects
				(font
					(size 1 1)
					(thickness 0.15)
				)
				(justify mirror)
			)
		)
		(property "Public" "False"
			(at 363.960001 -65.84 90)
			(layer "B.Fab")
			(hide yes)
			(effects
				(font
					(size 1 1)
					(thickness 0.15)
				)
				(justify mirror)
			)
		)
		(sheetname "Com Express 7 MGMT")
		(sheetfile "com_express_7_mgmt.kicad_sch")
		(attr exclude_from_pos_files exclude_from_bom)
		(fp_circle
			(center 0 0)
			(end 0.475 0)
			(stroke
				(width 0.05)
				(type default)
			)
			(fill no)
			(layer "B.CrtYd")
		)
		(pad "1" smd circle
			(at 0 0 180)
			(size 0.75 0.75)
			(layers "B.Cu" "B.Mask")
			(net 311 "Net-(J12D-~{THRMTRIP})")
			(pinfunction "1")
			(pintype "passive")
			(teardrops
				(best_length_ratio 0.4)
				(max_length 1)
				(best_width_ratio 0.9)
				(max_width 2)
				(curved_edges yes)
				(filter_ratio 0.9)
				(enabled yes)
				(allow_two_segments yes)
				(prefer_zone_connections yes)
			)
		)
	)
	(footprint "antmicro-footprints:TP_SMD_0.75mm"
		(layer "B.Cu")
		(at 217.58 124.85 45)
		(property "Reference" "TP46"
			(at 0.572756 0.021213 90)
			(layer "B.SilkS")
			(effects
				(font
					(size 0.7 0.7)
					(thickness 0.15)
				)
				(justify right bottom mirror)
			)
		)
		(property "Value" "TP_0.75mm_SMD"
			(at 0 -1.2 45)
			(layer "B.Fab")
			(effects
				(font
					(size 0.7 0.7)
					(thickness 0.15)
				)
				(justify right bottom mirror)
			)
		)
		(property "Author" "Antmicro"
			(at 152.009988 -117.284575 0)
			(layer "B.Fab")
			(hide yes)
			(effects
				(font
					(size 1 1)
					(thickness 0.15)
				)
				(justify mirror)
			)
		)
		(property "License" "Apache-2.0"
			(at 152.009988 -117.284575 0)
			(layer "B.Fab")
			(hide yes)
			(effects
				(font
					(size 1 1)
					(thickness 0.15)
				)
				(justify mirror)
			)
		)
		(property "MPN" ""
			(at 152.009988 -117.284575 0)
			(layer "B.Fab")
			(hide yes)
			(effects
				(font
					(size 1 1)
					(thickness 0.15)
				)
				(justify mirror)
			)
		)
		(property "Manufacturer" ""
			(at 152.009988 -117.284575 0)
			(layer "B.Fab")
			(hide yes)
			(effects
				(font
					(size 1 1)
					(thickness 0.15)
				)
				(justify mirror)
			)
		)
		(property "Public" "False"
			(at 152.009988 -117.284575 0)
			(layer "B.Fab")
			(hide yes)
			(effects
				(font
					(size 1 1)
					(thickness 0.15)
				)
				(justify mirror)
			)
		)
		(sheetname "PCIe misc")
		(sheetfile "pcie_misc.kicad_sch")
		(attr exclude_from_pos_files exclude_from_bom)
		(fp_circle
			(center 0 0)
			(end 0.475 0)
			(stroke
				(width 0.05)
				(type default)
			)
			(fill no)
			(layer "B.CrtYd")
		)
		(pad "1" smd circle
			(at 0 0 45)
			(size 0.75 0.75)
			(layers "B.Cu" "B.Mask")
			(net 711 "Net-(U37-SADR_{TRI})")
			(pinfunction "1")
			(pintype "passive")
			(teardrops
				(best_length_ratio 0.4)
				(max_length 1)
				(best_width_ratio 0.9)
				(max_width 2)
				(curved_edges yes)
				(filter_ratio 0.9)
				(enabled yes)
				(allow_two_segments yes)
				(prefer_zone_connections yes)
			)
		)
	)
	(footprint "antmicro-footprints:C_0402_1005Metric"
		(layer "B.Cu")
		(at 151.25 160.23 -90)
		(descr "Capacitor SMD 0402")
		(tags "capacitor SMD 0402")
		(property "Reference" "C24"
			(at -1.12 -2.45 90)
			(layer "B.SilkS")
			(effects
				(font
					(size 0.7 0.7)
					(thickness 0.15)
				)
				(justify left bottom mirror)
			)
		)
		(property "Value" "C_100n_0402"
			(at -1.022927 -2.155213 90)
			(layer "B.Fab")
			(effects
				(font
					(size 0.7 0.7)
					(thickness 0.15)
				)
				(justify left bottom mirror)
			)
		)
		(property "Datasheet" "https://www.murata.com/products/productdetail?partno=GRM155R61H104KE14%23"
			(at 0 0 270)
			(layer "F.Fab")
			(hide yes)
			(effects
				(font
					(size 1.27 1.27)
					(thickness 0.15)
				)
			)
		)
		(property "Author" "Antmicro"
			(at -8.98 311.48 0)
			(layer "B.Fab")
			(hide yes)
			(effects
				(font
					(size 1 1)
					(thickness 0.15)
				)
				(justify mirror)
			)
		)
		(property "Dielectric" "X5R"
			(at -8.98 311.48 0)
			(layer "B.Fab")
			(hide yes)
			(effects
				(font
					(size 1 1)
					(thickness 0.15)
				)
				(justify mirror)
			)
		)
		(property "License" "Apache-2.0"
			(at -8.98 311.48 0)
			(layer "B.Fab")
			(hide yes)
			(effects
				(font
					(size 1 1)
					(thickness 0.15)
				)
				(justify mirror)
			)
		)
		(property "MPN" "GRM155R61H104KE14D"
			(at -8.98 311.48 0)
			(layer "B.Fab")
			(hide yes)
			(effects
				(font
					(size 1 1)
					(thickness 0.15)
				)
				(justify mirror)
			)
		)
		(property "Manufacturer" "Murata"
			(at -8.98 311.48 0)
			(layer "B.Fab")
			(hide yes)
			(effects
				(font
					(size 1 1)
					(thickness 0.15)
				)
				(justify mirror)
			)
		)
		(property "Public" "False"
			(at -8.98 311.48 0)
			(layer "B.Fab")
			(hide yes)
			(effects
				(font
					(size 1 1)
					(thickness 0.15)
				)
				(justify mirror)
			)
		)
		(property "Val" "100n"
			(at -8.98 311.48 0)
			(layer "B.Fab")
			(hide yes)
			(effects
				(font
					(size 1 1)
					(thickness 0.15)
				)
				(justify mirror)
			)
		)
		(property "Voltage" "50V"
			(at -8.98 311.48 0)
			(layer "B.Fab")
			(hide yes)
			(effects
				(font
					(size 1 1)
					(thickness 0.15)
				)
				(justify mirror)
			)
		)
		(sheetname "2xSFP+")
		(sheetfile "2xSFP+.kicad_sch")
		(attr smd)
		(fp_rect
			(start -0.925 0.47)
			(end 0.925 -0.47)
			(stroke
				(width 0.05)
				(type default)
			)
			(fill no)
			(layer "B.CrtYd")
		)
		(fp_line
			(start -0.494 0.25)
			(end -0.494 -0.248)
			(stroke
				(width 0.15)
				(type solid)
			)
			(layer "B.Fab")
		)
		(fp_line
			(start 0.504 0.25)
			(end -0.494 0.25)
			(stroke
				(width 0.15)
				(type solid)
			)
			(layer "B.Fab")
		)
		(fp_line
			(start -0.494 -0.248)
			(end 0.504 -0.248)
			(stroke
				(width 0.15)
				(type solid)
			)
			(layer "B.Fab")
		)
		(fp_line
			(start 0.504 -0.248)
			(end 0.504 0.25)
			(stroke
				(width 0.15)
				(type solid)
			)
			(layer "B.Fab")
		)
		(pad "1" smd roundrect
			(at -0.48 0 270)
			(size 0.59 0.64)
			(layers "B.Cu" "B.Mask" "B.Paste")
			(roundrect_rratio 0.25)
			(net 1 "GND")
			(pintype "passive")
			(teardrops
				(best_length_ratio 0.2)
				(max_length 1)
				(best_width_ratio 0.9)
				(max_width 2)
				(curved_edges yes)
				(filter_ratio 0.9)
				(enabled yes)
				(allow_two_segments yes)
				(prefer_zone_connections yes)
			)
		)
		(pad "2" smd roundrect
			(at 0.48 0 270)
			(size 0.59 0.64)
			(layers "B.Cu" "B.Mask" "B.Paste")
			(roundrect_rratio 0.25)
			(net 2 "+3V3")
			(pintype "passive")
			(teardrops
				(best_length_ratio 0.2)
				(max_length 1)
				(best_width_ratio 0.9)
				(max_width 2)
				(curved_edges yes)
				(filter_ratio 0.9)
				(enabled yes)
				(allow_two_segments yes)
				(prefer_zone_connections yes)
			)
		)
	)
	(footprint "antmicro-footprints:C_0402_1005Metric"
		(layer "B.Cu")
		(at 132.29 136.36 -90)
		(descr "Capacitor SMD 0402")
		(tags "capacitor SMD 0402")
		(property "Reference" "C186"
			(at -1.25 0.54 90)
			(layer "B.SilkS")
			(effects
				(font
					(size 0.7 0.7)
					(thickness 0.15)
				)
				(justify left bottom mirror)
			)
		)
		(property "Value" "C_100n_0402"
			(at -1.022927 -2.155213 90)
			(layer "B.Fab")
			(effects
				(font
					(size 0.7 0.7)
					(thickness 0.15)
				)
				(justify left bottom mirror)
			)
		)
		(property "Datasheet" "https://www.murata.com/products/productdetail?partno=GRM155R61H104KE14%23"
			(at 0 0 270)
			(layer "F.Fab")
			(hide yes)
			(effects
				(font
					(size 1.27 1.27)
					(thickness 0.15)
				)
			)
		)
		(property "Author" "Antmicro"
			(at -4.07 268.65 0)
			(layer "B.Fab")
			(hide yes)
			(effects
				(font
					(size 1 1)
					(thickness 0.15)
				)
				(justify mirror)
			)
		)
		(property "Dielectric" "X5R"
			(at -4.07 268.65 0)
			(layer "B.Fab")
			(hide yes)
			(effects
				(font
					(size 1 1)
					(thickness 0.15)
				)
				(justify mirror)
			)
		)
		(property "License" "Apache-2.0"
			(at -4.07 268.65 0)
			(layer "B.Fab")
			(hide yes)
			(effects
				(font
					(size 1 1)
					(thickness 0.15)
				)
				(justify mirror)
			)
		)
		(property "MPN" "GRM155R61H104KE14D"
			(at -4.07 268.65 0)
			(layer "B.Fab")
			(hide yes)
			(effects
				(font
					(size 1 1)
					(thickness 0.15)
				)
				(justify mirror)
			)
		)
		(property "Manufacturer" "Murata"
			(at -4.07 268.65 0)
			(layer "B.Fab")
			(hide yes)
			(effects
				(font
					(size 1 1)
					(thickness 0.15)
				)
				(justify mirror)
			)
		)
		(property "Public" "False"
			(at -4.07 268.65 0)
			(layer "B.Fab")
			(hide yes)
			(effects
				(font
					(size 1 1)
					(thickness 0.15)
				)
				(justify mirror)
			)
		)
		(property "Val" "100n"
			(at -4.07 268.65 0)
			(layer "B.Fab")
			(hide yes)
			(effects
				(font
					(size 1 1)
					(thickness 0.15)
				)
				(justify mirror)
			)
		)
		(property "Voltage" "50V"
			(at -4.07 268.65 0)
			(layer "B.Fab")
			(hide yes)
			(effects
				(font
					(size 1 1)
					(thickness 0.15)
				)
				(justify mirror)
			)
		)
		(sheetname "KR to SFI #2")
		(sheetfile "kr_sfi.kicad_sch")
		(attr smd)
		(fp_rect
			(start -0.925 0.47)
			(end 0.925 -0.47)
			(stroke
				(width 0.05)
				(type default)
			)
			(fill no)
			(layer "B.CrtYd")
		)
		(fp_line
			(start -0.494 0.25)
			(end -0.494 -0.248)
			(stroke
				(width 0.15)
				(type solid)
			)
			(layer "B.Fab")
		)
		(fp_line
			(start 0.504 0.25)
			(end -0.494 0.25)
			(stroke
				(width 0.15)
				(type solid)
			)
			(layer "B.Fab")
		)
		(fp_line
			(start -0.494 -0.248)
			(end 0.504 -0.248)
			(stroke
				(width 0.15)
				(type solid)
			)
			(layer "B.Fab")
		)
		(fp_line
			(start 0.504 -0.248)
			(end 0.504 0.25)
			(stroke
				(width 0.15)
				(type solid)
			)
			(layer "B.Fab")
		)
		(pad "1" smd roundrect
			(at -0.48 0 270)
			(size 0.59 0.64)
			(layers "B.Cu" "B.Mask" "B.Paste")
			(roundrect_rratio 0.25)
			(net 1 "GND")
			(pintype "passive")
			(teardrops
				(best_length_ratio 0.2)
				(max_length 1)
				(best_width_ratio 0.9)
				(max_width 2)
				(curved_edges yes)
				(filter_ratio 0.9)
				(enabled yes)
				(allow_two_segments yes)
				(prefer_zone_connections yes)
			)
		)
		(pad "2" smd roundrect
			(at 0.48 0 270)
			(size 0.59 0.64)
			(layers "B.Cu" "B.Mask" "B.Paste")
			(roundrect_rratio 0.25)
			(net 74 "+1V0")
			(pintype "passive")
			(teardrops
				(best_length_ratio 0.2)
				(max_length 1)
				(best_width_ratio 0.9)
				(max_width 2)
				(curved_edges yes)
				(filter_ratio 0.9)
				(enabled yes)
				(allow_two_segments yes)
				(prefer_zone_connections yes)
			)
		)
	)
)
